# S9S_MB_2U (Grand Teton) — schematic netlist excerpt (pin names and nets, part order shuffled) for the footprints in the layout excerpt that follows; sources: Cadence DE-HDL packaged netlist, KiCad conversion of 03242023_DA0F0TMBIJ0_F0T_Motherboard_J_brd_V01_OCP.brd

PL16  Q_INDUCTOR  BLM18SN220TN1D/8000MA IND  pkg SMLF  page 263 : \1\ = P12V_AUX ; \2\ = SW_P1V8_PCH_AUX_FLT
R1346  Q_RES  100 1% CHIP  pkg 0402LF  page 239 : A = P0V7_JTAG_VREF_2 ; B = GND

(kicad_pcb
	(version 20260206)
	(generator "pcbnew")
	(generator_version "10.0")
	(general
		(thickness 1.6)
		(legacy_teardrops no)
	)
	(paper "A4")
	(title_block
		(title "03242023_DA0F0TMBIJ0_F0T_Motherboard_J_brd_V01_OCP.brd")
		(comment 1 "Grand Teton / footprints 3813-3814 of 6105")
	)
	(layers
		(0 "F.Cu" signal "TOP")
		(4 "In1.Cu" signal "GND")
		(6 "In2.Cu" signal "IN1")
		(8 "In3.Cu" signal "GND1")
		(10 "In4.Cu" signal "IN2")
		(12 "In5.Cu" signal "GND2")
		(14 "In6.Cu" signal "IN3")
		(16 "In7.Cu" signal "GND3")
		(18 "In8.Cu" signal "VCC")
		(20 "In9.Cu" signal "VCC1")
		(22 "In10.Cu" signal "GND4")
		(24 "In11.Cu" signal "IN4")
		(26 "In12.Cu" signal "GND5")
		(28 "In13.Cu" signal "IN5")
		(30 "In14.Cu" signal "GND6")
		(32 "In15.Cu" signal "IN6")
		(34 "In16.Cu" signal "GND7")
		(2 "B.Cu" signal "BOTTOM")
		(9 "F.Adhes" user "F.Adhesive")
		(11 "B.Adhes" user "B.Adhesive")
		(13 "F.Paste" user "Package Geometry/Pastemask Top")
		(15 "B.Paste" user "Package Geometry/Pastemask Bottom")
		(5 "F.SilkS" user "Ref Des/Silkscreen Top")
		(7 "B.SilkS" user "Ref Des/Silkscreen Bottom")
		(1 "F.Mask" user "Board Geometry/Soldermask Top")
		(3 "B.Mask" user "Board Geometry/Soldermask Bottom")
		(17 "Dwgs.User" user "User.Drawings")
		(19 "Cmts.User" user "User.Comments")
		(21 "Eco1.User" user "User.Eco1")
		(23 "Eco2.User" user "User.Eco2")
		(25 "Edge.Cuts" user "Board Geometry/Outline")
		(27 "Margin" user)
		(31 "F.CrtYd" user "Package Geometry/Place Bound Top")
		(29 "B.CrtYd" user "Package Geometry/Place Bound Bottom")
		(35 "F.Fab" user "Ref Des/Assembly Top")
		(33 "B.Fab" user "Ref Des/Assembly Bottom")
	)
	(footprint ""
		(layer "F.Cu")
		(at 391.672572 -76.460604 -90)
		(property "Reference" "PL16"
			(at 0 0 270)
			(layer "F.SilkS")
			(hide yes)
			(effects
				(font
					(size 1.27 1.27)
				)
			)
		)
		(property "Value" ""
			(at 0 0 270)
			(layer "F.Fab")
			(effects
				(font
					(size 1.27 1.27)
				)
			)
		)
		(duplicate_pad_numbers_are_jumpers no)
		(fp_line
			(start -1.27 0.5842)
			(end -1.27 -0.5842)
			(stroke
				(width 0.1524)
				(type default)
			)
			(layer "F.SilkS")
		)
		(fp_line
			(start -0.127 0.5842)
			(end -0.127 -0.5842)
			(stroke
				(width 0.1524)
				(type default)
			)
			(layer "F.SilkS")
		)
		(fp_line
			(start 0.127 0.5842)
			(end 0.127 -0.5842)
			(stroke
				(width 0.1524)
				(type default)
			)
			(layer "F.SilkS")
		)
		(fp_line
			(start 1.27 0.5842)
			(end -1.27 0.5842)
			(stroke
				(width 0.1524)
				(type default)
			)
			(layer "F.SilkS")
		)
		(fp_line
			(start 1.27 0.5842)
			(end 1.27 -0.5842)
			(stroke
				(width 0.1524)
				(type default)
			)
			(layer "F.SilkS")
		)
		(fp_line
			(start -1.27 -0.5588)
			(end -1.27 -0.5842)
			(stroke
				(width 0.1524)
				(type default)
			)
			(layer "F.SilkS")
		)
		(fp_line
			(start -1.27 -0.5842)
			(end 1.27 -0.5842)
			(stroke
				(width 0.1524)
				(type default)
			)
			(layer "F.SilkS")
		)
		(fp_line
			(start -0.9144 0.508)
			(end -0.9144 0.406654)
			(stroke
				(width 0.1)
				(type default)
			)
			(layer "F.Fab")
		)
		(fp_line
			(start 0.9144 0.508)
			(end -0.9144 0.508)
			(stroke
				(width 0.1)
				(type default)
			)
			(layer "F.Fab")
		)
		(fp_line
			(start -1.194308 0.406654)
			(end -1.194308 -0.406654)
			(stroke
				(width 0.1)
				(type default)
			)
			(layer "F.Fab")
		)
		(fp_line
			(start -0.9144 0.406654)
			(end -1.194308 0.406654)
			(stroke
				(width 0.1)
				(type default)
			)
			(layer "F.Fab")
		)
		(fp_line
			(start 0.9144 0.4064)
			(end 0.9144 0.508)
			(stroke
				(width 0.1)
				(type default)
			)
			(layer "F.Fab")
		)
		(fp_line
			(start 1.1938 0.4064)
			(end 0.9144 0.4064)
			(stroke
				(width 0.1)
				(type default)
			)
			(layer "F.Fab")
		)
		(fp_line
			(start -1.194308 -0.406654)
			(end -0.9144 -0.406654)
			(stroke
				(width 0.1)
				(type default)
			)
			(layer "F.Fab")
		)
		(fp_line
			(start -0.9144 -0.406654)
			(end -0.9144 -0.508)
			(stroke
				(width 0.1)
				(type default)
			)
			(layer "F.Fab")
		)
		(fp_line
			(start 0.9144 -0.406654)
			(end 1.1938 -0.406654)
			(stroke
				(width 0.1)
				(type default)
			)
			(layer "F.Fab")
		)
		(fp_line
			(start 1.1938 -0.406654)
			(end 1.1938 0.4064)
			(stroke
				(width 0.1)
				(type default)
			)
			(layer "F.Fab")
		)
		(fp_line
			(start -0.9144 -0.508)
			(end 0.9144 -0.508)
			(stroke
				(width 0.1)
				(type default)
			)
			(layer "F.Fab")
		)
		(fp_line
			(start 0.9144 -0.508)
			(end 0.9144 -0.406654)
			(stroke
				(width 0.1)
				(type default)
			)
			(layer "F.Fab")
		)
		(pad "1" smd rect
			(at -0.7366 0 180)
			(size 0.7112 0.8128)
			(layers "F.Cu" "F.Mask" "F.Paste")
			(net "P12V_AUX")
		)
		(pad "2" smd rect
			(at 0.7366 0 180)
			(size 0.7112 0.8128)
			(layers "F.Cu" "F.Mask" "F.Paste")
			(net "SW_P1V8_PCH_AUX_FLT")
		)
	)
	(footprint ""
		(layer "F.Cu")
		(at 376.8852 -107.183428 180)
		(property "Reference" "R1346"
			(at 0 0 180)
			(layer "F.SilkS")
			(hide yes)
			(effects
				(font
					(size 1.27 1.27)
				)
			)
		)
		(property "Value" ""
			(at 0 0 180)
			(layer "F.Fab")
			(effects
				(font
					(size 1.27 1.27)
				)
			)
		)
		(duplicate_pad_numbers_are_jumpers no)
		(fp_line
			(start 0.7874 0.4064)
			(end -0.7874 0.4064)
			(stroke
				(width 0.1524)
				(type default)
			)
			(layer "F.SilkS")
		)
		(fp_line
			(start 0.7874 -0.4064)
			(end 0.7874 0.4064)
			(stroke
				(width 0.1524)
				(type default)
			)
			(layer "F.SilkS")
		)
		(fp_line
			(start -0.7874 0.4064)
			(end -0.7874 -0.4064)
			(stroke
				(width 0.1524)
				(type default)
			)
			(layer "F.SilkS")
		)
		(fp_line
			(start -0.7874 -0.4064)
			(end 0.7874 -0.4064)
			(stroke
				(width 0.1524)
				(type default)
			)
			(layer "F.SilkS")
		)
		(fp_line
			(start 0.67945 0.3048)
			(end 0.120396 0.3048)
			(stroke
				(width 0.1)
				(type default)
			)
			(layer "F.Fab")
		)
		(fp_line
			(start 0.67945 -0.3048)
			(end 0.67945 0.3048)
			(stroke
				(width 0.1)
				(type default)
			)
			(layer "F.Fab")
		)
		(fp_line
			(start 0.12065 -0.2794)
			(end 0.12065 -0.3048)
			(stroke
				(width 0.1)
				(type default)
			)
			(layer "F.Fab")
		)
		(fp_line
			(start 0.12065 -0.3048)
			(end 0.67945 -0.3048)
			(stroke
				(width 0.1)
				(type default)
			)
			(layer "F.Fab")
		)
		(fp_line
			(start 0.120396 0.3048)
			(end 0.120396 0.2794)
			(stroke
				(width 0.1)
				(type default)
			)
			(layer "F.Fab")
		)
		(fp_line
			(start 0.120396 0.2794)
			(end -0.12065 0.2794)
			(stroke
				(width 0.1)
				(type default)
			)
			(layer "F.Fab")
		)
		(fp_line
			(start -0.12065 0.3048)
			(end -0.67945 0.3048)
			(stroke
				(width 0.1)
				(type default)
			)
			(layer "F.Fab")
		)
		(fp_line
			(start -0.12065 0.2794)
			(end -0.12065 0.3048)
			(stroke
				(width 0.1)
				(type default)
			)
			(layer "F.Fab")
		)
		(fp_line
			(start -0.12065 -0.2794)
			(end 0.12065 -0.2794)
			(stroke
				(width 0.1)
				(type default)
			)
			(layer "F.Fab")
		)
		(fp_line
			(start -0.12065 -0.305054)
			(end -0.12065 -0.2794)
			(stroke
				(width 0.1)
				(type default)
			)
			(layer "F.Fab")
		)
		(fp_line
			(start -0.67945 0.3048)
			(end -0.67945 -0.305054)
			(stroke
				(width 0.1)
				(type default)
			)
			(layer "F.Fab")
		)
		(fp_line
			(start -0.67945 -0.305054)
			(end -0.12065 -0.305054)
			(stroke
				(width 0.1)
				(type default)
			)
			(layer "F.Fab")
		)
		(pad "1" smd circle
			(at -0.40005 0 180)
			(size 0 0)
			(layers "F.Cu" "F.Mask" "F.Paste")
			(net "P0V7_JTAG_VREF_2")
		)
		(pad "2" smd circle
			(at 0.40005 0 180)
			(size 0 0)
			(layers "F.Cu" "F.Mask" "F.Paste")
			(net "GND")
		)
	)
)
